(kicad_pcb
	(version 20260206)
	(generator "pcbnew")
	(generator_version "10.0")
	(general
		(thickness 1.6)
		(legacy_teardrops no)
	)
	(paper "A4")
	(title_block
		(title "Bryce Canyon_F.DPB_16315-1-OCP.brd")
		(comment 1 "Bryce Canyon / footprints 1359-1365 of 2223")
	)
	(layers
		(0 "F.Cu" signal "TOP")
		(4 "In1.Cu" signal "L2GND")
		(6 "In2.Cu" signal "L3")
		(8 "In3.Cu" signal "L4GND")
		(10 "In4.Cu" signal "L5")
		(12 "In5.Cu" signal "L6VCC")
		(14 "In6.Cu" signal "L7VCC")
		(16 "In7.Cu" signal "L8")
		(18 "In8.Cu" signal "L9GND")
		(20 "In9.Cu" signal "L10")
		(22 "In10.Cu" signal "L11GND")
		(2 "B.Cu" signal "BOTTOM")
		(9 "F.Adhes" user "F.Adhesive")
		(11 "B.Adhes" user "B.Adhesive")
		(13 "F.Paste" user "Package Geometry/Pastemask Top")
		(15 "B.Paste" user "Package Geometry/Pastemask Bottom")
		(5 "F.SilkS" user "Ref Des/Silkscreen Top")
		(7 "B.SilkS" user "Ref Des/Silkscreen Bottom")
		(1 "F.Mask" user "Board Geometry/Soldermask Top")
		(3 "B.Mask" user "Board Geometry/Soldermask Bottom")
		(17 "Dwgs.User" user "User.Drawings")
		(19 "Cmts.User" user "User.Comments")
		(21 "Eco1.User" user "User.Eco1")
		(23 "Eco2.User" user "User.Eco2")
		(25 "Edge.Cuts" user "Board Geometry/Outline")
		(27 "Margin" user)
		(31 "F.CrtYd" user "Package Geometry/Place Bound Top")
		(29 "B.CrtYd" user "Package Geometry/Place Bound Bottom")
		(35 "F.Fab" user "Ref Des/Assembly Top")
		(33 "B.Fab" user "Ref Des/Assembly Bottom")
	)
	(footprint ""
		(layer "F.Cu")
		(at 172.593 -59.857894)
		(property "Reference" "Q176"
			(at 0 0 0)
			(layer "F.SilkS")
			(hide yes)
			(effects
				(font
					(size 1.27 1.27)
				)
			)
		)
		(property "Value" "AO4407AL-GP"
			(at -3.707384 -1.5367 0)
			(unlocked yes)
			(layer "F.Fab")
			(hide yes)
			(effects
				(font
					(size 1.016 1.016)
					(thickness 0.1524)
				)
			)
		)
		(property "Device Type" "SOIC8H69"
			(at -3.707384 -3.0607 0)
			(unlocked yes)
			(layer "F.Fab")
			(hide yes)
			(effects
				(font
					(size 1.016 1.016)
					(thickness 0.1524)
				)
			)
		)
		(duplicate_pad_numbers_are_jumpers no)
		(fp_line
			(start -2.7432 -1.4224)
			(end -2.7432 1.4224)
			(stroke
				(width 0.1524)
				(type default)
			)
			(layer "F.SilkS")
		)
		(fp_line
			(start -2.7432 1.4224)
			(end -2.6416 1.4224)
			(stroke
				(width 0.1524)
				(type default)
			)
			(layer "F.SilkS")
		)
		(fp_line
			(start -2.7432 1.4224)
			(end 2.1336 1.4224)
			(stroke
				(width 0.1524)
				(type default)
			)
			(layer "F.SilkS")
		)
		(fp_line
			(start -2.7178 -0.508)
			(end -2.1844 -0.0508)
			(stroke
				(width 0.1524)
				(type default)
			)
			(layer "F.SilkS")
		)
		(fp_line
			(start -2.6289 3.4417)
			(end -2.6289 1.4732)
			(stroke
				(width 0.381)
				(type default)
			)
			(layer "F.SilkS")
		)
		(fp_line
			(start -2.1844 -0.0508)
			(end -2.7178 0.508)
			(stroke
				(width 0.1524)
				(type default)
			)
			(layer "F.SilkS")
		)
		(fp_line
			(start 2.1336 -1.4224)
			(end -2.7432 -1.4224)
			(stroke
				(width 0.1524)
				(type default)
			)
			(layer "F.SilkS")
		)
		(fp_line
			(start 2.1336 1.4224)
			(end 2.1336 -1.4224)
			(stroke
				(width 0.1524)
				(type default)
			)
			(layer "F.SilkS")
		)
		(fp_poly
			(pts
				(xy -2.2098 -1.4224) (xy -2.2098 1.4224) (xy 2.2098 1.4224) (xy 2.2098 -1.4224)
			)
			(stroke
				(width 0)
				(type default)
			)
			(fill yes)
			(layer "F.SilkS")
		)
		(fp_rect
			(start -2.450084 2.999994)
			(end 2.450084 -2.999994)
			(stroke
				(width 0)
				(type default)
			)
			(fill no)
			(layer "F.CrtYd")
		)
		(fp_poly
			(pts
				(xy -2.8194 3.6322) (xy -2.8194 -3.6322) (xy 2.8194 -3.6322) (xy 2.8194 1.18364) (xy 2.450084 1.18364)
				(xy 2.450084 -2.999994) (xy -2.450084 -2.999994) (xy -2.450084 2.999994) (xy 2.450084 2.999994)
				(xy 2.450084 1.18618) (xy 2.8194 1.18618) (xy 2.8194 3.6322)
			)
			(stroke
				(width 0)
				(type default)
			)
			(fill no)
			(layer "F.CrtYd")
		)
		(fp_rect
			(start -2.8194 3.6322)
			(end 2.8194 -3.6322)
			(stroke
				(width 0)
				(type default)
			)
			(fill no)
			(layer "F.Fab")
		)
		(pad "1" smd rect
			(at -1.905 2.54)
			(size 0.635 1.651)
			(layers "F.Cu" "F.Mask" "F.Paste")
			(net "P12V_A")
		)
		(pad "2" smd rect
			(at -0.635 2.54)
			(size 0.635 1.651)
			(layers "F.Cu" "F.Mask" "F.Paste")
			(net "P12V_A")
		)
		(pad "3" smd rect
			(at 0.635 2.54)
			(size 0.635 1.651)
			(layers "F.Cu" "F.Mask" "F.Paste")
			(net "P12V_A")
		)
		(pad "4" smd rect
			(at 1.905 2.54)
			(size 0.635 1.651)
			(layers "F.Cu" "F.Mask" "F.Paste")
			(net "SW_HDD_N29")
		)
		(pad "5" smd rect
			(at 1.905 -2.54)
			(size 0.635 1.651)
			(layers "F.Cu" "F.Mask" "F.Paste")
			(net "P12V_HDD29")
		)
		(pad "6" smd rect
			(at 0.635 -2.54)
			(size 0.635 1.651)
			(layers "F.Cu" "F.Mask" "F.Paste")
			(net "P12V_HDD29")
		)
		(pad "7" smd rect
			(at -0.635 -2.54)
			(size 0.635 1.651)
			(layers "F.Cu" "F.Mask" "F.Paste")
			(net "P12V_HDD29")
		)
		(pad "8" smd rect
			(at -1.905 -2.54)
			(size 0.635 1.651)
			(layers "F.Cu" "F.Mask" "F.Paste")
			(net "P12V_HDD29")
		)
	)
	(footprint ""
		(layer "F.Cu")
		(at 16.874998 -276.649942 180)
		(property "Reference" "D36"
			(at 0 0 180)
			(layer "F.SilkS")
			(hide yes)
			(effects
				(font
					(size 1.27 1.27)
				)
			)
		)
		(property "Value" "RB551V30-GP"
			(at 0 -6.7818 180)
			(unlocked yes)
			(layer "F.Fab")
			(hide yes)
			(effects
				(font
					(size 1.016 1.016)
					(thickness 0.1524)
				)
			)
		)
		(property "Device Type" "SOD323AKH38"
			(at 0 -8.6868 180)
			(unlocked yes)
			(layer "F.Fab")
			(hide yes)
			(effects
				(font
					(size 1.016 1.016)
					(thickness 0.1524)
				)
			)
		)
		(duplicate_pad_numbers_are_jumpers no)
		(fp_line
			(start 0.889 2.159)
			(end -0.889 2.159)
			(stroke
				(width 0.1524)
				(type default)
			)
			(layer "F.SilkS")
		)
		(fp_line
			(start 0.889 -1.9304)
			(end 0.889 2.159)
			(stroke
				(width 0.1524)
				(type default)
			)
			(layer "F.SilkS")
		)
		(fp_line
			(start 0.762 2.0574)
			(end -0.762 2.0574)
			(stroke
				(width 0.508)
				(type default)
			)
			(layer "F.SilkS")
		)
		(fp_line
			(start -0.889 2.159)
			(end -0.889 -1.9304)
			(stroke
				(width 0.1524)
				(type default)
			)
			(layer "F.SilkS")
		)
		(fp_line
			(start -0.889 -1.9304)
			(end 0.889 -1.9304)
			(stroke
				(width 0.1524)
				(type default)
			)
			(layer "F.SilkS")
		)
		(fp_rect
			(start -1.016 2.3114)
			(end 1.016 -2.0066)
			(stroke
				(width 0)
				(type default)
			)
			(fill no)
			(layer "F.CrtYd")
		)
		(fp_poly
			(pts
				(xy -1.016 -2.0066) (xy 1.016 -2.0066) (xy 1.016 2.3114) (xy -1.016 2.3114)
			)
			(stroke
				(width 0)
				(type default)
			)
			(fill no)
			(layer "F.Fab")
		)
		(pad "A" smd rect
			(at 0 -1.143 180)
			(size 0.5588 1.016)
			(layers "F.Cu" "F.Mask" "F.Paste")
			(net "SW_HDD_R0")
		)
		(pad "K" smd rect
			(at 0 1.143 180)
			(size 0.5588 1.016)
			(layers "F.Cu" "F.Mask" "F.Paste")
			(net "SW_HDD_N0")
		)
	)
	(footprint ""
		(layer "F.Cu")
		(at 265.77417 -371.731794)
		(property "Reference" "R1173"
			(at 0 0 0)
			(layer "F.SilkS")
			(hide yes)
			(effects
				(font
					(size 1.27 1.27)
				)
			)
		)
		(property "Value" "10R5F-1-GP"
			(at 0 -8.9535 0)
			(unlocked yes)
			(layer "F.Fab")
			(hide yes)
			(effects
				(font
					(size 1.27 1.016)
					(thickness 0.1524)
				)
			)
		)
		(property "Device Type" "R805H24"
			(at 0 -10.6299 0)
			(unlocked yes)
			(layer "F.Fab")
			(hide yes)
			(effects
				(font
					(size 1.27 1.016)
					(thickness 0.1524)
				)
			)
		)
		(duplicate_pad_numbers_are_jumpers no)
		(fp_line
			(start -0.889 -1.7018)
			(end -0.889 0.2794)
			(stroke
				(width 0.1524)
				(type default)
			)
			(layer "F.SilkS")
		)
		(fp_line
			(start -0.889 0.0762)
			(end -0.889 1.7018)
			(stroke
				(width 0.1524)
				(type default)
			)
			(layer "F.SilkS")
		)
		(fp_line
			(start -0.889 1.7018)
			(end 0.889 1.7018)
			(stroke
				(width 0.1524)
				(type default)
			)
			(layer "F.SilkS")
		)
		(fp_line
			(start 0.889 -1.7018)
			(end -0.889 -1.7018)
			(stroke
				(width 0.1524)
				(type default)
			)
			(layer "F.SilkS")
		)
		(fp_line
			(start 0.889 -1.7018)
			(end 0.889 -0.381)
			(stroke
				(width 0.1524)
				(type default)
			)
			(layer "F.SilkS")
		)
		(fp_line
			(start 0.889 1.7018)
			(end 0.889 -0.508)
			(stroke
				(width 0.1524)
				(type default)
			)
			(layer "F.SilkS")
		)
		(fp_poly
			(pts
				(xy 0.9652 -1.778) (xy 0.9652 1.778) (xy -0.9652 1.778) (xy -0.9652 -1.778)
			)
			(stroke
				(width 0)
				(type default)
			)
			(fill no)
			(layer "F.CrtYd")
		)
		(fp_rect
			(start -0.9652 1.778)
			(end 0.9652 -1.778)
			(stroke
				(width 0)
				(type default)
			)
			(fill no)
			(layer "F.Fab")
		)
		(pad "1" smd rect
			(at 0 -0.9652)
			(size 1.397 1.143)
			(layers "F.Cu" "F.Mask" "F.Paste")
			(net "MB3_12V_CTRL_GATE2")
		)
		(pad "2" smd rect
			(at 0 0.9652)
			(size 1.397 1.143)
			(layers "F.Cu" "F.Mask" "F.Paste")
			(net "MB3_CM_GATE_R")
		)
	)
	(footprint ""
		(layer "F.Cu")
		(at 236.855 -381.4318)
		(property "Reference" "C588"
			(at 0 0 0)
			(layer "F.SilkS")
			(hide yes)
			(effects
				(font
					(size 1.27 1.27)
				)
			)
		)
		(property "Value" "SC2D2U25V5KX-2-GP"
			(at -0.0762 -6.1214 0)
			(unlocked yes)
			(layer "F.Fab")
			(hide yes)
			(effects
				(font
					(size 1.016 1.016)
					(thickness 0.1524)
				)
			)
		)
		(property "Device Type" "C805H54"
			(at -0.0762 -8.1534 0)
			(unlocked yes)
			(layer "F.Fab")
			(hide yes)
			(effects
				(font
					(size 1.016 1.016)
					(thickness 0.1524)
				)
			)
		)
		(duplicate_pad_numbers_are_jumpers no)
		(fp_line
			(start 0.635 0)
			(end -0.635 0)
			(stroke
				(width 0.508)
				(type default)
			)
			(layer "F.SilkS")
		)
		(fp_rect
			(start -0.9652 1.778)
			(end 0.9652 -1.778)
			(stroke
				(width 0)
				(type default)
			)
			(fill no)
			(layer "F.CrtYd")
		)
		(fp_poly
			(pts
				(xy -0.9652 -1.778) (xy 0.9652 -1.778) (xy 0.9652 1.778) (xy -0.9652 1.778)
			)
			(stroke
				(width 0)
				(type default)
			)
			(fill no)
			(layer "F.Fab")
		)
		(pad "1" smd rect
			(at 0 -0.9652)
			(size 1.397 1.143)
			(layers "F.Cu" "F.Mask" "F.Paste")
			(net "P12V_A_PGOOD")
		)
		(pad "2" smd rect
			(at 0 0.9652)
			(size 1.397 1.143)
			(layers "F.Cu" "F.Mask" "F.Paste")
			(net "GND")
		)
	)
	(footprint ""
		(layer "F.Cu")
		(at 373.5578 -145.8214 180)
		(property "Reference" "R1089"
			(at 0 0 180)
			(layer "F.SilkS")
			(hide yes)
			(effects
				(font
					(size 1.27 1.27)
				)
			)
		)
		(property "Value" "3K83R2F-GP"
			(at 0.064008 -3.993896 180)
			(unlocked yes)
			(layer "F.Fab")
			(hide yes)
			(effects
				(font
					(size 1.016 1.016)
					(thickness 0.1524)
				)
			)
		)
		(property "Device Type" "R402H16"
			(at 0.064008 -5.517896 180)
			(unlocked yes)
			(layer "F.Fab")
			(hide yes)
			(effects
				(font
					(size 1.016 1.016)
					(thickness 0.1524)
				)
			)
		)
		(duplicate_pad_numbers_are_jumpers no)
		(fp_line
			(start 0.508 -0.9398)
			(end -0.508 -0.9398)
			(stroke
				(width 0.1524)
				(type default)
			)
			(layer "F.SilkS")
		)
		(fp_line
			(start -0.508 -0.9398)
			(end -0.508 0.9398)
			(stroke
				(width 0.1524)
				(type default)
			)
			(layer "F.SilkS")
		)
		(fp_rect
			(start -0.508 0.9398)
			(end 0.508 -0.9398)
			(stroke
				(width 0)
				(type default)
			)
			(fill no)
			(layer "F.CrtYd")
		)
		(fp_rect
			(start -0.508 0.9398)
			(end 0.508 -0.9398)
			(stroke
				(width 0)
				(type default)
			)
			(fill no)
			(layer "F.Fab")
		)
		(pad "1" smd custom
			(at 0 -0.4445 180)
			(size 0.1397 0.1397)
			(layers "F.Cu" "F.Mask" "F.Paste")
			(net "COMP_B_PGOOD")
			(options
				(clearance outline)
				(anchor circle)
			)
			(primitives
				(gr_poly
					(pts
						(arc
							(start -0.1778 -0.2794)
							(mid -0.249642 -0.249642)
							(end -0.2794 -0.1778)
						)
						(arc
							(start -0.2794 0.1778)
							(mid -0.249642 0.249642)
							(end -0.1778 0.2794)
						)
						(arc
							(start 0.1778 0.2794)
							(mid 0.249642 0.249642)
							(end 0.2794 0.1778)
						)
						(arc
							(start 0.2794 -0.1778)
							(mid 0.249642 -0.249642)
							(end 0.1778 -0.2794)
						)
					)
					(width 0)
					(fill yes)
				)
			)
		)
		(pad "2" smd custom
			(at 0 0.4445 180)
			(size 0.1397 0.1397)
			(layers "F.Cu" "F.Mask" "F.Paste")
			(net "GND")
			(options
				(clearance outline)
				(anchor circle)
			)
			(primitives
				(gr_poly
					(pts
						(arc
							(start -0.1778 -0.2794)
							(mid -0.249642 -0.249642)
							(end -0.2794 -0.1778)
						)
						(arc
							(start -0.2794 0.1778)
							(mid -0.249642 0.249642)
							(end -0.1778 0.2794)
						)
						(arc
							(start 0.1778 0.2794)
							(mid 0.249642 0.249642)
							(end 0.2794 0.1778)
						)
						(arc
							(start 0.2794 -0.1778)
							(mid 0.249642 -0.249642)
							(end 0.1778 -0.2794)
						)
					)
					(width 0)
					(fill yes)
				)
			)
		)
	)
	(footprint ""
		(layer "F.Cu")
		(at 146.630898 -278.554942 180)
		(property "Reference" "Q25"
			(at 0 0 180)
			(layer "F.SilkS")
			(hide yes)
			(effects
				(font
					(size 1.27 1.27)
				)
			)
		)
		(property "Value" "2N7002KDW-GP"
			(at -2.3622 -8.2042 180)
			(unlocked yes)
			(layer "F.Fab")
			(hide yes)
			(effects
				(font
					(size 1.016 1.016)
					(thickness 0.1524)
				)
			)
		)
		(property "Device Type" "SOT-363H44"
			(at -2.3622 -10.1092 180)
			(unlocked yes)
			(layer "F.Fab")
			(hide yes)
			(effects
				(font
					(size 1.016 1.016)
					(thickness 0.1524)
				)
			)
		)
		(duplicate_pad_numbers_are_jumpers no)
		(fp_line
			(start 1.4478 1.7018)
			(end 1.4478 -1.7018)
			(stroke
				(width 0.1524)
				(type default)
			)
			(layer "F.SilkS")
		)
		(fp_line
			(start 1.4478 -1.7018)
			(end -1.4478 -1.7018)
			(stroke
				(width 0.1524)
				(type default)
			)
			(layer "F.SilkS")
		)
		(fp_line
			(start -1.27 1.524)
			(end -1.27 0.6604)
			(stroke
				(width 0.4826)
				(type default)
			)
			(layer "F.SilkS")
		)
		(fp_line
			(start -1.4478 1.7018)
			(end 1.4478 1.7018)
			(stroke
				(width 0.1524)
				(type default)
			)
			(layer "F.SilkS")
		)
		(fp_line
			(start -1.4478 -1.7018)
			(end -1.4478 1.7018)
			(stroke
				(width 0.1524)
				(type default)
			)
			(layer "F.SilkS")
		)
		(fp_poly
			(pts
				(xy -1.524 -1.778) (xy 1.524 -1.778) (xy 1.524 1.778) (xy -1.524 1.778)
			)
			(stroke
				(width 0)
				(type default)
			)
			(fill no)
			(layer "F.CrtYd")
		)
		(fp_poly
			(pts
				(xy -1.524 -1.778) (xy 1.524 -1.778) (xy 1.524 1.778) (xy -1.524 1.778)
			)
			(stroke
				(width 0)
				(type default)
			)
			(fill no)
			(layer "F.Fab")
		)
		(pad "1" smd rect
			(at -0.65024 0.9398 180)
			(size 0.4064 1.016)
			(layers "F.Cu" "F.Mask" "F.Paste")
			(net "GND")
		)
		(pad "2" smd rect
			(at 0 0.9398 180)
			(size 0.4064 1.016)
			(layers "F.Cu" "F.Mask" "F.Paste")
			(net "SW_PWR_R_HDD4")
		)
		(pad "3" smd rect
			(at 0.65024 0.9398 180)
			(size 0.4064 1.016)
			(layers "F.Cu" "F.Mask" "F.Paste")
			(net "SW_HDD_P4")
		)
		(pad "4" smd rect
			(at 0.65024 -0.9398 180)
			(size 0.4064 1.016)
			(layers "F.Cu" "F.Mask" "F.Paste")
			(net "GND")
		)
		(pad "5" smd rect
			(at 0 -0.9398 180)
			(size 0.4064 1.016)
			(layers "F.Cu" "F.Mask" "F.Paste")
			(net "SW_HDD_G4")
		)
		(pad "6" smd rect
			(at -0.65024 -0.9398 180)
			(size 0.4064 1.016)
			(layers "F.Cu" "F.Mask" "F.Paste")
			(net "SW_HDD_R4")
		)
	)
	(footprint ""
		(layer "F.Cu")
		(at 111.524796 -46.649894 180)
		(property "Reference" "D27"
			(at 0 0 180)
			(layer "F.SilkS")
			(hide yes)
			(effects
				(font
					(size 1.27 1.27)
				)
			)
		)
		(property "Value" "RB551V30-GP"
			(at 0 -6.7818 180)
			(unlocked yes)
			(layer "F.Fab")
			(hide yes)
			(effects
				(font
					(size 1.016 1.016)
					(thickness 0.1524)
				)
			)
		)
		(property "Device Type" "SOD323AKH38"
			(at 0 -8.6868 180)
			(unlocked yes)
			(layer "F.Fab")
			(hide yes)
			(effects
				(font
					(size 1.016 1.016)
					(thickness 0.1524)
				)
			)
		)
		(duplicate_pad_numbers_are_jumpers no)
		(fp_line
			(start 0.889 2.159)
			(end -0.889 2.159)
			(stroke
				(width 0.1524)
				(type default)
			)
			(layer "F.SilkS")
		)
		(fp_line
			(start 0.889 -1.9304)
			(end 0.889 2.159)
			(stroke
				(width 0.1524)
				(type default)
			)
			(layer "F.SilkS")
		)
		(fp_line
			(start 0.762 2.0574)
			(end -0.762 2.0574)
			(stroke
				(width 0.508)
				(type default)
			)
			(layer "F.SilkS")
		)
		(fp_line
			(start -0.889 2.159)
			(end -0.889 -1.9304)
			(stroke
				(width 0.1524)
				(type default)
			)
			(layer "F.SilkS")
		)
		(fp_line
			(start -0.889 -1.9304)
			(end 0.889 -1.9304)
			(stroke
				(width 0.1524)
				(type default)
			)
			(layer "F.SilkS")
		)
		(fp_rect
			(start -1.016 2.3114)
			(end 1.016 -2.0066)
			(stroke
				(width 0)
				(type default)
			)
			(fill no)
			(layer "F.CrtYd")
		)
		(fp_poly
			(pts
				(xy -1.016 -2.0066) (xy 1.016 -2.0066) (xy 1.016 2.3114) (xy -1.016 2.3114)
			)
			(stroke
				(width 0)
				(type default)
			)
			(fill no)
			(layer "F.Fab")
		)
		(pad "A" smd rect
			(at 0 -1.143 180)
			(size 0.5588 1.016)
			(layers "F.Cu" "F.Mask" "F.Paste")
			(net "SW_HDD_R27")
		)
		(pad "K" smd rect
			(at 0 1.143 180)
			(size 0.5588 1.016)
			(layers "F.Cu" "F.Mask" "F.Paste")
			(net "SW_HDD_N27")
		)
	)
)
